(kicad_pcb
	(version 20241229)
	(generator "pcbnew")
	(generator_version "9.0")
	(general
		(thickness 1.552)
		(legacy_teardrops no)
	)
	(paper "A4")
	(title_block
		(date "2023-07-25")
		(rev "1.1.4")
		(comment 9 "footprints 287-290 of 379")
	)
	(layers
		(0 "F.Cu" signal)
		(4 "In1.Cu" signal)
		(6 "In2.Cu" signal)
		(8 "In3.Cu" signal)
		(10 "In4.Cu" signal)
		(12 "In5.Cu" signal)
		(14 "In6.Cu" signal)
		(2 "B.Cu" signal)
		(9 "F.Adhes" user "F.Adhesive")
		(11 "B.Adhes" user "B.Adhesive")
		(13 "F.Paste" user)
		(15 "B.Paste" user)
		(5 "F.SilkS" user "F.Silkscreen")
		(7 "B.SilkS" user "B.Silkscreen")
		(1 "F.Mask" user)
		(3 "B.Mask" user)
		(17 "Dwgs.User" user "User.Drawings")
		(19 "Cmts.User" user "User.Comments")
		(21 "Eco1.User" user "User.Eco1")
		(23 "Eco2.User" user "User.Eco2")
		(25 "Edge.Cuts" user)
		(27 "Margin" user)
		(31 "F.CrtYd" user "F.Courtyard")
		(29 "B.CrtYd" user "B.Courtyard")
		(35 "F.Fab" user)
		(33 "B.Fab" user)
	)
	(footprint "antmicro-footprints:C_0201"
		(layer "B.Cu")
		(at 121.9 93.9 45)
		(descr "Capacitor SMD 0201")
		(tags "capacitor SMD 0201")
		(property "Reference" "C75"
			(at 1.29099 -15.249278 45)
			(layer "B.SilkS")
			(effects
				(font
					(size 0.65 0.65)
					(thickness 0.15)
				)
				(justify right bottom mirror)
			)
		)
		(property "Value" "C_100n_0201"
			(at 0 -1.399999 45)
			(layer "B.Fab")
			(hide yes)
			(effects
				(font
					(size 0.7 0.7)
					(thickness 0.15)
				)
				(justify right bottom mirror)
			)
		)
		(property "Datasheet" "https://www.yageo.com/en/Chart/Download/pdf/CC0201KRX6S5BB104"
			(at 0 0 45)
			(layer "F.Fab")
			(hide yes)
			(effects
				(font
					(size 1.27 1.27)
					(thickness 0.15)
				)
			)
		)
		(property "Description" "SMD Multilayer Ceramic Capacitor, 0.1 µF, 6.3 V, 0201 [0603 Metric], ± 10%, X6S, CC Series"
			(at 0 0 45)
			(layer "F.Fab")
			(hide yes)
			(effects
				(font
					(size 1.27 1.27)
					(thickness 0.15)
				)
			)
		)
		(property "Author" "Antmicro"
			(at 102.10101 -58.693644 0)
			(layer "B.Fab")
			(hide yes)
			(effects
				(font
					(size 1 1)
					(thickness 0.15)
				)
				(justify mirror)
			)
		)
		(property "Dielectric" ""
			(at 102.10101 -58.693644 0)
			(layer "B.Fab")
			(hide yes)
			(effects
				(font
					(size 1 1)
					(thickness 0.15)
				)
				(justify mirror)
			)
		)
		(property "License" "Apache-2.0"
			(at 102.10101 -58.693644 0)
			(layer "B.Fab")
			(hide yes)
			(effects
				(font
					(size 1 1)
					(thickness 0.15)
				)
				(justify mirror)
			)
		)
		(property "MPN" "CC0201KRX6S5BB104"
			(at 102.10101 -58.693644 0)
			(layer "B.Fab")
			(hide yes)
			(effects
				(font
					(size 1 1)
					(thickness 0.15)
				)
				(justify mirror)
			)
		)
		(property "Manufacturer" "YAGEO"
			(at 102.10101 -58.693644 0)
			(layer "B.Fab")
			(hide yes)
			(effects
				(font
					(size 1 1)
					(thickness 0.15)
				)
				(justify mirror)
			)
		)
		(property "Val" "100n"
			(at 102.10101 -58.693644 0)
			(layer "B.Fab")
			(hide yes)
			(effects
				(font
					(size 1 1)
					(thickness 0.15)
				)
				(justify mirror)
			)
		)
		(property "Voltage" ""
			(at 102.10101 -58.693644 0)
			(layer "B.Fab")
			(hide yes)
			(effects
				(font
					(size 1 1)
					(thickness 0.15)
				)
				(justify mirror)
			)
		)
		(property "Public" "False"
			(at 0 0 45)
			(unlocked yes)
			(layer "B.Fab")
			(hide yes)
			(effects
				(font
					(size 1 1)
					(thickness 0.15)
				)
				(justify mirror)
			)
		)
		(sheetname "/FPGA/")
		(sheetfile "fpga.kicad_sch")
		(attr smd)
		(fp_poly
			(pts
				(xy -0.7 0.35) (xy 0.7 0.35) (xy 0.7 -0.35) (xy -0.7 -0.35)
			)
			(stroke
				(width 0.05)
				(type default)
			)
			(fill no)
			(layer "B.CrtYd")
		)
		(fp_poly
			(pts
				(xy 0.3 -0.15) (xy -0.301 -0.15) (xy -0.301 0.149) (xy 0.3 0.149)
			)
			(stroke
				(width 0.15)
				(type solid)
			)
			(fill no)
			(layer "B.Fab")
		)
		(fp_text user "License: Apache-2.0"
			(at -0.72 -4.4 225)
			(layer "B.Fab")
			(effects
				(font
					(size 0.7 0.7)
					(thickness 0.15)
				)
				(justify left bottom mirror)
			)
		)
		(fp_text user "${REFERENCE}"
			(at -0.72 -3.4 225)
			(layer "B.Fab")
			(effects
				(font
					(size 0.7 0.7)
					(thickness 0.15)
				)
				(justify left bottom mirror)
			)
		)
		(fp_text user "Author: Antmicro"
			(at -0.72 -5.400001 225)
			(layer "B.Fab")
			(effects
				(font
					(size 0.7 0.7)
					(thickness 0.15)
				)
				(justify left bottom mirror)
			)
		)
		(pad "" smd roundrect
			(at -0.349 0.002 45)
			(size 0.318 0.36)
			(layers "B.Paste")
			(roundrect_rratio 0.25)
		)
		(pad "" smd roundrect
			(at 0.341 0.002 45)
			(size 0.318 0.36)
			(layers "B.Paste")
			(roundrect_rratio 0.25)
		)
		(pad "1" smd roundrect
			(at -0.321 0.002 45)
			(size 0.46 0.4)
			(layers "B.Cu" "B.Mask")
			(roundrect_rratio 0.25)
			(net 1 "GND")
			(pintype "passive")
		)
		(pad "2" smd roundrect
			(at 0.32 0.002 45)
			(size 0.46 0.4)
			(layers "B.Cu" "B.Mask")
			(roundrect_rratio 0.25)
			(net 2 "+3V3")
			(pintype "passive")
		)
	)
	(footprint "antmicro-footprints:R_0402_1005Metric"
		(layer "B.Cu")
		(at 137.49 57.35)
		(descr "Resistor SMD 0402")
		(tags "resistor SMD 0402")
		(property "Reference" "R1"
			(at 2.34 0.39 180)
			(layer "B.SilkS")
			(effects
				(font
					(size 0.65 0.65)
					(thickness 0.15)
				)
				(justify left bottom mirror)
			)
		)
		(property "Value" "R_100k_0402"
			(at 0 -1.4 180)
			(layer "B.Fab")
			(hide yes)
			(effects
				(font
					(size 0.7 0.7)
					(thickness 0.15)
				)
				(justify left bottom mirror)
			)
		)
		(property "Datasheet" "https://www.bourns.com/docs/product-datasheets/cr.pdf"
			(at 0 0 0)
			(layer "F.Fab")
			(hide yes)
			(effects
				(font
					(size 1.27 1.27)
					(thickness 0.15)
				)
			)
		)
		(property "Description" "SMD Chip Resistor, 100 kohm, ± 1%, 62.5 mW, 0402 [1005 Metric], Thick Film, General Purpose"
			(at 0 0 0)
			(layer "F.Fab")
			(hide yes)
			(effects
				(font
					(size 1.27 1.27)
					(thickness 0.15)
				)
			)
		)
		(property "Author" "Antmicro"
			(at 0 0 0)
			(layer "B.Fab")
			(hide yes)
			(effects
				(font
					(size 1 1)
					(thickness 0.15)
				)
				(justify mirror)
			)
		)
		(property "License" "Apache-2.0"
			(at 0 0 0)
			(layer "B.Fab")
			(hide yes)
			(effects
				(font
					(size 1 1)
					(thickness 0.15)
				)
				(justify mirror)
			)
		)
		(property "MPN" "CR0402-FX-1003GLF"
			(at 0 0 0)
			(layer "B.Fab")
			(hide yes)
			(effects
				(font
					(size 1 1)
					(thickness 0.15)
				)
				(justify mirror)
			)
		)
		(property "Manufacturer" "Bourns"
			(at 0 0 0)
			(layer "B.Fab")
			(hide yes)
			(effects
				(font
					(size 1 1)
					(thickness 0.15)
				)
				(justify mirror)
			)
		)
		(property "Tolerance" "1%"
			(at 0 0 0)
			(layer "B.Fab")
			(hide yes)
			(effects
				(font
					(size 1 1)
					(thickness 0.15)
				)
				(justify mirror)
			)
		)
		(property "Val" "100k"
			(at 0 0 0)
			(layer "B.Fab")
			(hide yes)
			(effects
				(font
					(size 1 1)
					(thickness 0.15)
				)
				(justify mirror)
			)
		)
		(sheetname "/Power Supply/")
		(sheetfile "supply.kicad_sch")
		(attr smd)
		(fp_rect
			(start -0.925 0.47)
			(end 0.925 -0.47)
			(stroke
				(width 0.05)
				(type default)
			)
			(fill no)
			(layer "B.CrtYd")
		)
		(fp_rect
			(start -0.5 0.25)
			(end 0.5 -0.25)
			(stroke
				(width 0.15)
				(type solid)
			)
			(fill no)
			(layer "B.Fab")
		)
		(fp_text user "Author: Antmicro"
			(at -0.95 -4.169 180)
			(layer "B.Fab")
			(effects
				(font
					(size 0.7 0.7)
					(thickness 0.15)
				)
				(justify left bottom mirror)
			)
		)
		(fp_text user "License: Apache-2.0"
			(at -0.95 -5.169 180)
			(layer "B.Fab")
			(effects
				(font
					(size 0.7 0.7)
					(thickness 0.15)
				)
				(justify left bottom mirror)
			)
		)
		(fp_text user "${REFERENCE}"
			(at -0.95 -3.168 180)
			(layer "B.Fab")
			(effects
				(font
					(size 0.7 0.7)
					(thickness 0.15)
				)
				(justify left bottom mirror)
			)
		)
		(pad "1" smd roundrect
			(at -0.48 0)
			(size 0.59 0.64)
			(layers "B.Cu" "B.Mask" "B.Paste")
			(roundrect_rratio 0.25)
			(net 262 "Net-(U1-V_{TT_EN})")
			(pintype "passive")
		)
		(pad "2" smd roundrect
			(at 0.48 0)
			(size 0.59 0.64)
			(layers "B.Cu" "B.Mask" "B.Paste")
			(roundrect_rratio 0.25)
			(net 2 "+3V3")
			(pintype "passive")
		)
	)
	(footprint "antmicro-footprints:C_0201"
		(layer "B.Cu")
		(at 125.9 95.1)
		(descr "Capacitor SMD 0201")
		(tags "capacitor SMD 0201")
		(property "Reference" "C96"
			(at -10.27 -12.095736 0)
			(layer "B.SilkS")
			(effects
				(font
					(size 0.65 0.65)
					(thickness 0.15)
				)
				(justify right bottom mirror)
			)
		)
		(property "Value" "C_100n_0201"
			(at 0 -1.4 0)
			(layer "B.Fab")
			(hide yes)
			(effects
				(font
					(size 0.7 0.7)
					(thickness 0.15)
				)
				(justify right bottom mirror)
			)
		)
		(property "Datasheet" "https://www.yageo.com/en/Chart/Download/pdf/CC0201KRX6S5BB104"
			(at 0 0 0)
			(layer "F.Fab")
			(hide yes)
			(effects
				(font
					(size 1.27 1.27)
					(thickness 0.15)
				)
			)
		)
		(property "Description" "SMD Multilayer Ceramic Capacitor, 0.1 µF, 6.3 V, 0201 [0603 Metric], ± 10%, X6S, CC Series"
			(at 0 0 0)
			(layer "F.Fab")
			(hide yes)
			(effects
				(font
					(size 1.27 1.27)
					(thickness 0.15)
				)
			)
		)
		(property "Author" "Antmicro"
			(at 0 0 0)
			(layer "B.Fab")
			(hide yes)
			(effects
				(font
					(size 1 1)
					(thickness 0.15)
				)
				(justify mirror)
			)
		)
		(property "Dielectric" ""
			(at 0 0 0)
			(layer "B.Fab")
			(hide yes)
			(effects
				(font
					(size 1 1)
					(thickness 0.15)
				)
				(justify mirror)
			)
		)
		(property "License" "Apache-2.0"
			(at 0 0 0)
			(layer "B.Fab")
			(hide yes)
			(effects
				(font
					(size 1 1)
					(thickness 0.15)
				)
				(justify mirror)
			)
		)
		(property "MPN" "CC0201KRX6S5BB104"
			(at 0 0 0)
			(layer "B.Fab")
			(hide yes)
			(effects
				(font
					(size 1 1)
					(thickness 0.15)
				)
				(justify mirror)
			)
		)
		(property "Manufacturer" "YAGEO"
			(at 0 0 0)
			(layer "B.Fab")
			(hide yes)
			(effects
				(font
					(size 1 1)
					(thickness 0.15)
				)
				(justify mirror)
			)
		)
		(property "Val" "100n"
			(at 0 0 0)
			(layer "B.Fab")
			(hide yes)
			(effects
				(font
					(size 1 1)
					(thickness 0.15)
				)
				(justify mirror)
			)
		)
		(property "Voltage" ""
			(at 0 0 0)
			(layer "B.Fab")
			(hide yes)
			(effects
				(font
					(size 1 1)
					(thickness 0.15)
				)
				(justify mirror)
			)
		)
		(property "Public" "False"
			(at 0 0 0)
			(unlocked yes)
			(layer "B.Fab")
			(hide yes)
			(effects
				(font
					(size 1 1)
					(thickness 0.15)
				)
				(justify mirror)
			)
		)
		(sheetname "/FPGA Power/")
		(sheetfile "FPGA_Power.kicad_sch")
		(attr smd)
		(fp_rect
			(start -0.7 0.35)
			(end 0.7 -0.35)
			(stroke
				(width 0.05)
				(type default)
			)
			(fill no)
			(layer "B.CrtYd")
		)
		(fp_rect
			(start 0.3 -0.15)
			(end -0.301 0.149)
			(stroke
				(width 0.15)
				(type solid)
			)
			(fill no)
			(layer "B.Fab")
		)
		(fp_text user "License: Apache-2.0"
			(at -0.72 -4.4 180)
			(layer "B.Fab")
			(effects
				(font
					(size 0.7 0.7)
					(thickness 0.15)
				)
				(justify left bottom mirror)
			)
		)
		(fp_text user "Author: Antmicro"
			(at -0.72 -5.4 180)
			(layer "B.Fab")
			(effects
				(font
					(size 0.7 0.7)
					(thickness 0.15)
				)
				(justify left bottom mirror)
			)
		)
		(fp_text user "${REFERENCE}"
			(at -0.72 -3.4 180)
			(layer "B.Fab")
			(effects
				(font
					(size 0.7 0.7)
					(thickness 0.15)
				)
				(justify left bottom mirror)
			)
		)
		(pad "" smd roundrect
			(at -0.349 0.002)
			(size 0.318 0.36)
			(layers "B.Paste")
			(roundrect_rratio 0.25)
		)
		(pad "" smd roundrect
			(at 0.341 0.002)
			(size 0.318 0.36)
			(layers "B.Paste")
			(roundrect_rratio 0.25)
		)
		(pad "1" smd roundrect
			(at -0.321 0.002)
			(size 0.46 0.4)
			(layers "B.Cu" "B.Mask")
			(roundrect_rratio 0.25)
			(net 1 "GND")
			(pintype "passive")
		)
		(pad "2" smd roundrect
			(at 0.32 0.002)
			(size 0.46 0.4)
			(layers "B.Cu" "B.Mask")
			(roundrect_rratio 0.25)
			(net 12 "/FPGA Power/VCC_ADPHY")
			(pintype "passive")
		)
	)
	(footprint "antmicro-footprints:R_0402_1005Metric"
		(layer "B.Cu")
		(at 94.27 92.25 180)
		(descr "Resistor SMD 0402")
		(tags "resistor SMD 0402")
		(property "Reference" "R139"
			(at 1.04 -0.39 0)
			(layer "B.SilkS")
			(effects
				(font
					(size 0.65 0.65)
					(thickness 0.15)
				)
				(justify left bottom mirror)
			)
		)
		(property "Value" "R_1k_0402"
			(at 0 -1.4 0)
			(layer "B.Fab")
			(hide yes)
			(effects
				(font
					(size 0.7 0.7)
					(thickness 0.15)
				)
				(justify left bottom mirror)
			)
		)
		(property "Datasheet" "https://www.bourns.com/docs/product-datasheets/cr.pdf"
			(at 0 0 180)
			(layer "F.Fab")
			(hide yes)
			(effects
				(font
					(size 1.27 1.27)
					(thickness 0.15)
				)
			)
		)
		(property "Description" "SMD Chip Resistor, 1 kohm, ± 1%, 63 mW, 0402 [1005 Metric], Thick Film, General Purpose"
			(at 0 0 180)
			(layer "F.Fab")
			(hide yes)
			(effects
				(font
					(size 1.27 1.27)
					(thickness 0.15)
				)
			)
		)
		(property "Author" "Antmicro"
			(at 188.54 184.5 0)
			(layer "B.Fab")
			(hide yes)
			(effects
				(font
					(size 1 1)
					(thickness 0.15)
				)
				(justify mirror)
			)
		)
		(property "License" "Apache-2.0"
			(at 188.54 184.5 0)
			(layer "B.Fab")
			(hide yes)
			(effects
				(font
					(size 1 1)
					(thickness 0.15)
				)
				(justify mirror)
			)
		)
		(property "MPN" "CR0402-FX-1001GLF"
			(at 188.54 184.5 0)
			(layer "B.Fab")
			(hide yes)
			(effects
				(font
					(size 1 1)
					(thickness 0.15)
				)
				(justify mirror)
			)
		)
		(property "Manufacturer" "Bourns"
			(at 188.54 184.5 0)
			(layer "B.Fab")
			(hide yes)
			(effects
				(font
					(size 1 1)
					(thickness 0.15)
				)
				(justify mirror)
			)
		)
		(property "Tolerance" "1%"
			(at 188.54 184.5 0)
			(layer "B.Fab")
			(hide yes)
			(effects
				(font
					(size 1 1)
					(thickness 0.15)
				)
				(justify mirror)
			)
		)
		(property "Val" "1k"
			(at 188.54 184.5 0)
			(layer "B.Fab")
			(hide yes)
			(effects
				(font
					(size 1 1)
					(thickness 0.15)
				)
				(justify mirror)
			)
		)
		(sheetname "/SDI/")
		(sheetfile "sdi.kicad_sch")
		(attr smd)
		(fp_rect
			(start -0.925 0.47)
			(end 0.925 -0.47)
			(stroke
				(width 0.05)
				(type default)
			)
			(fill no)
			(layer "B.CrtYd")
		)
		(fp_rect
			(start -0.5 0.25)
			(end 0.5 -0.25)
			(stroke
				(width 0.15)
				(type solid)
			)
			(fill no)
			(layer "B.Fab")
		)
		(fp_text user "Author: Antmicro"
			(at -0.95 -4.169 0)
			(layer "B.Fab")
			(effects
				(font
					(size 0.7 0.7)
					(thickness 0.15)
				)
				(justify left bottom mirror)
			)
		)
		(fp_text user "${REFERENCE}"
			(at -0.95 -3.168 0)
			(layer "B.Fab")
			(effects
				(font
					(size 0.7 0.7)
					(thickness 0.15)
				)
				(justify left bottom mirror)
			)
		)
		(fp_text user "License: Apache-2.0"
			(at -0.95 -5.169 0)
			(layer "B.Fab")
			(effects
				(font
					(size 0.7 0.7)
					(thickness 0.15)
				)
				(justify left bottom mirror)
			)
		)
		(pad "1" smd roundrect
			(at -0.48 0 180)
			(size 0.59 0.64)
			(layers "B.Cu" "B.Mask" "B.Paste")
			(roundrect_rratio 0.25)
			(net 198 "/SDI/AUDIO_EN{slash}~{DIS}")
			(pintype "passive")
		)
		(pad "2" smd roundrect
			(at 0.48 0 180)
			(size 0.59 0.64)
			(layers "B.Cu" "B.Mask" "B.Paste")
			(roundrect_rratio 0.25)
			(net 2 "+3V3")
			(pintype "passive")
		)
	)
)
